(kicad_pcb
	(version 20260206)
	(generator "pcbnew")
	(generator_version "10.0")
	(general
		(thickness 1.6)
		(legacy_teardrops no)
	)
	(paper "A4")
	(title_block
		(title "v1-chassis-manager — T6M_CM_d_v01_1031_1645.brd")
		(comment 1 "Open CloudServer (Microsoft) / footprints 633-641 of 2512")
	)
	(layers
		(0 "F.Cu" signal "TOP")
		(4 "In1.Cu" signal "GND1")
		(6 "In2.Cu" signal "IN1")
		(8 "In3.Cu" signal "VCC1")
		(10 "In4.Cu" signal "VCC2")
		(12 "In5.Cu" signal "GND2")
		(14 "In6.Cu" signal "IN2")
		(16 "In7.Cu" signal "IN3")
		(18 "In8.Cu" signal "GND3")
		(2 "B.Cu" signal "BOTTOM")
		(9 "F.Adhes" user "F.Adhesive")
		(11 "B.Adhes" user "B.Adhesive")
		(13 "F.Paste" user "Package Geometry/Pastemask Top")
		(15 "B.Paste" user "Package Geometry/Pastemask Bottom")
		(5 "F.SilkS" user "Ref Des/Silkscreen Top")
		(7 "B.SilkS" user "Ref Des/Silkscreen Bottom")
		(1 "F.Mask" user "Board Geometry/Soldermask Top")
		(3 "B.Mask" user "Board Geometry/Soldermask Bottom")
		(17 "Dwgs.User" user "User.Drawings")
		(19 "Cmts.User" user "User.Comments")
		(21 "Eco1.User" user "User.Eco1")
		(23 "Eco2.User" user "User.Eco2")
		(25 "Edge.Cuts" user "Board Geometry/Outline")
		(27 "Margin" user)
		(31 "F.CrtYd" user "Package Geometry/Place Bound Top")
		(29 "B.CrtYd" user "Package Geometry/Place Bound Bottom")
		(35 "F.Fab" user "Ref Des/Assembly Top")
		(33 "B.Fab" user "Ref Des/Assembly Bottom")
	)
	(footprint ""
		(layer "F.Cu")
		(at 15.301468 -54.773322 -90)
		(property "Reference" "C504"
			(at 1.05918 -14.450314 90)
			(unlocked yes)
			(layer "F.SilkS")
			(effects
				(font
					(size 0.7874 0.5842)
					(thickness 0.1524)
				)
			)
		)
		(property "Value" ""
			(at 0 0 270)
			(layer "F.Fab")
			(effects
				(font
					(size 1.27 1.27)
				)
			)
		)
		(duplicate_pad_numbers_are_jumpers no)
		(fp_line
			(start -1.2954 0.5842)
			(end -1.2954 -0.5842)
			(stroke
				(width 0.1524)
				(type default)
			)
			(layer "F.SilkS")
		)
		(fp_line
			(start 1.2954 0.5842)
			(end -1.2954 0.5842)
			(stroke
				(width 0.1524)
				(type default)
			)
			(layer "F.SilkS")
		)
		(fp_line
			(start -1.2954 -0.5842)
			(end 1.2954 -0.5842)
			(stroke
				(width 0.1524)
				(type default)
			)
			(layer "F.SilkS")
		)
		(fp_line
			(start 0 -0.5842)
			(end 0 0.5842)
			(stroke
				(width 0.1524)
				(type default)
			)
			(layer "F.SilkS")
		)
		(fp_line
			(start 1.2954 -0.5842)
			(end 1.2954 0.5842)
			(stroke
				(width 0.1524)
				(type default)
			)
			(layer "F.SilkS")
		)
		(fp_poly
			(pts
				(xy 0.8636 -0.4572) (xy 0.8636 -0.3556) (xy 1.143 -0.3556) (xy 1.143 0.3556) (xy 0.8636 0.3556)
				(xy 0.8636 0.4572) (xy -0.8636 0.4572) (xy -0.8636 0.3556) (xy -1.143 0.3556) (xy -1.143 -0.3556)
				(xy -0.8636 -0.3556) (xy -0.8636 -0.4572)
			)
			(stroke
				(width 0)
				(type default)
			)
			(fill no)
			(layer "F.CrtYd")
		)
		(fp_line
			(start -0.884936 0.504952)
			(end -0.884936 -0.504952)
			(stroke
				(width 0.1)
				(type default)
			)
			(layer "F.Fab")
		)
		(fp_line
			(start 0.884936 0.504952)
			(end -0.884936 0.504952)
			(stroke
				(width 0.1)
				(type default)
			)
			(layer "F.Fab")
		)
		(fp_line
			(start -0.884936 -0.504952)
			(end 0.884936 -0.504952)
			(stroke
				(width 0.1)
				(type default)
			)
			(layer "F.Fab")
		)
		(fp_line
			(start 0.884936 -0.504952)
			(end 0.884936 0.504952)
			(stroke
				(width 0.1)
				(type default)
			)
			(layer "F.Fab")
		)
		(pad "1" smd rect
			(at 0.7366 0)
			(size 0.7112 0.8128)
			(layers "F.Cu" "F.Mask" "F.Paste")
			(net "CRT_B")
		)
		(pad "2" smd rect
			(at -0.7366 0)
			(size 0.7112 0.8128)
			(layers "F.Cu" "F.Mask" "F.Paste")
			(net "GND")
		)
	)
	(footprint ""
		(layer "F.Cu")
		(at 129.27457 -26.569416 -90)
		(property "Reference" "R1141"
			(at 5.325618 -0.028448 90)
			(unlocked yes)
			(layer "F.SilkS")
			(effects
				(font
					(size 0.7874 0.5842)
					(thickness 0.1524)
				)
				(justify left)
			)
		)
		(property "Value" ""
			(at 0 0 270)
			(layer "F.Fab")
			(effects
				(font
					(size 1.27 1.27)
				)
			)
		)
		(duplicate_pad_numbers_are_jumpers no)
		(fp_line
			(start -0.7874 0.4064)
			(end -0.7874 -0.4064)
			(stroke
				(width 0.1524)
				(type default)
			)
			(layer "F.SilkS")
		)
		(fp_line
			(start 0.7874 0.4064)
			(end -0.7874 0.4064)
			(stroke
				(width 0.1524)
				(type default)
			)
			(layer "F.SilkS")
		)
		(fp_line
			(start -0.7874 -0.4064)
			(end 0.7874 -0.4064)
			(stroke
				(width 0.1524)
				(type default)
			)
			(layer "F.SilkS")
		)
		(fp_line
			(start 0.7874 -0.4064)
			(end 0.7874 0.4064)
			(stroke
				(width 0.1524)
				(type default)
			)
			(layer "F.SilkS")
		)
		(fp_poly
			(pts
				(xy -0.508 0.2794) (xy -0.508 0.2286) (xy -0.635 0.2286) (xy -0.635 -0.254) (xy -0.5334 -0.254)
				(xy -0.5334 -0.2794) (xy 0.5334 -0.2794) (xy 0.5334 -0.254) (xy 0.635 -0.254) (xy 0.635 0.254) (xy 0.5334 0.254)
				(xy 0.5334 0.2794)
			)
			(stroke
				(width 0)
				(type default)
			)
			(fill no)
			(layer "F.CrtYd")
		)
		(pad "1" smd rect
			(at 0.40005 0 270)
			(size 0.4572 0.508)
			(layers "F.Cu" "F.Mask" "F.Paste")
			(net "P3V3_STB_NODE1")
		)
		(pad "2" smd rect
			(at -0.40005 0 270)
			(size 0.4572 0.508)
			(layers "F.Cu" "F.Mask" "F.Paste")
			(net "SIO_PIN76")
		)
	)
	(footprint ""
		(layer "F.Cu")
		(at 113.215166 -135.285734 -90)
		(property "Reference" "PC108"
			(at -1.990852 -5.870448 90)
			(unlocked yes)
			(layer "F.SilkS")
			(effects
				(font
					(size 0.635 0.4064)
					(thickness 0.1524)
				)
				(justify left)
			)
		)
		(property "Value" ""
			(at 0 0 270)
			(layer "F.Fab")
			(effects
				(font
					(size 1.27 1.27)
				)
			)
		)
		(duplicate_pad_numbers_are_jumpers no)
		(fp_line
			(start -0.7874 0.4064)
			(end -0.7874 -0.4064)
			(stroke
				(width 0.1524)
				(type default)
			)
			(layer "F.SilkS")
		)
		(fp_line
			(start 0.7874 0.4064)
			(end -0.7874 0.4064)
			(stroke
				(width 0.1524)
				(type default)
			)
			(layer "F.SilkS")
		)
		(fp_line
			(start 0 0.381)
			(end 0 -0.381)
			(stroke
				(width 0.1524)
				(type default)
			)
			(layer "F.SilkS")
		)
		(fp_line
			(start -0.7874 -0.4064)
			(end 0.7874 -0.4064)
			(stroke
				(width 0.1524)
				(type default)
			)
			(layer "F.SilkS")
		)
		(fp_line
			(start 0.7874 -0.4064)
			(end 0.7874 0.4064)
			(stroke
				(width 0.1524)
				(type default)
			)
			(layer "F.SilkS")
		)
		(fp_poly
			(pts
				(xy -0.5334 0.254) (xy -0.635 0.254) (xy -0.635 0.2286) (xy -0.635 -0.254) (xy -0.5334 -0.254) (xy -0.5334 -0.2794)
				(xy 0.5334 -0.2794) (xy 0.5334 -0.254) (xy 0.635 -0.254) (xy 0.635 0.254) (xy 0.5334 0.254) (xy 0.5334 0.2794)
				(xy -0.508 0.2794) (xy -0.5334 0.2794)
			)
			(stroke
				(width 0)
				(type default)
			)
			(fill no)
			(layer "F.CrtYd")
		)
		(pad "1" smd rect
			(at 0.40005 0 270)
			(size 0.4572 0.508)
			(layers "F.Cu" "F.Mask" "F.Paste")
			(net "VR_PVCCP_NODE1_COMP")
		)
		(pad "2" smd rect
			(at -0.40005 0 270)
			(size 0.4572 0.508)
			(layers "F.Cu" "F.Mask" "F.Paste")
			(net "AGND_PVCCP_NODE1")
		)
	)
	(footprint ""
		(layer "F.Cu")
		(at 82.429096 -151.688292)
		(property "Reference" "PR3"
			(at 1.086104 0.663194 0)
			(unlocked yes)
			(layer "F.SilkS")
			(effects
				(font
					(size 0.7874 0.5842)
					(thickness 0.1524)
				)
				(justify left)
			)
		)
		(property "Value" ""
			(at 0 0 0)
			(layer "F.Fab")
			(effects
				(font
					(size 1.27 1.27)
				)
			)
		)
		(duplicate_pad_numbers_are_jumpers no)
		(fp_line
			(start -0.7874 -0.4064)
			(end 0.7874 -0.4064)
			(stroke
				(width 0.1524)
				(type default)
			)
			(layer "F.SilkS")
		)
		(fp_line
			(start -0.7874 0.4064)
			(end -0.7874 -0.4064)
			(stroke
				(width 0.1524)
				(type default)
			)
			(layer "F.SilkS")
		)
		(fp_line
			(start 0.7874 -0.4064)
			(end 0.7874 0.4064)
			(stroke
				(width 0.1524)
				(type default)
			)
			(layer "F.SilkS")
		)
		(fp_line
			(start 0.7874 0.4064)
			(end -0.7874 0.4064)
			(stroke
				(width 0.1524)
				(type default)
			)
			(layer "F.SilkS")
		)
		(fp_poly
			(pts
				(xy -0.508 0.2794) (xy -0.508 0.2286) (xy -0.635 0.2286) (xy -0.635 -0.254) (xy -0.5334 -0.254)
				(xy -0.5334 -0.2794) (xy 0.5334 -0.2794) (xy 0.5334 -0.254) (xy 0.635 -0.254) (xy 0.635 0.254) (xy 0.5334 0.254)
				(xy 0.5334 0.2794)
			)
			(stroke
				(width 0)
				(type default)
			)
			(fill no)
			(layer "F.CrtYd")
		)
		(pad "1" smd rect
			(at 0.40005 0)
			(size 0.4572 0.508)
			(layers "F.Cu" "F.Mask" "F.Paste")
			(net "P5V_STB_NODE1_FB")
		)
		(pad "2" smd rect
			(at -0.40005 0)
			(size 0.4572 0.508)
			(layers "F.Cu" "F.Mask" "F.Paste")
			(net "P5V_STB_NODE1")
		)
	)
	(footprint ""
		(layer "F.Cu")
		(at 35.243008 -185.604404)
		(property "Reference" "C767"
			(at -1.53162 -5.211064 0)
			(unlocked yes)
			(layer "F.SilkS")
			(effects
				(font
					(size 0.7874 0.5842)
					(thickness 0.1524)
				)
				(justify left)
			)
		)
		(property "Value" ""
			(at 0 0 0)
			(layer "F.Fab")
			(effects
				(font
					(size 1.27 1.27)
				)
			)
		)
		(duplicate_pad_numbers_are_jumpers no)
		(fp_line
			(start -0.7874 -0.4064)
			(end 0.7874 -0.4064)
			(stroke
				(width 0.1524)
				(type default)
			)
			(layer "F.SilkS")
		)
		(fp_line
			(start -0.7874 0.4064)
			(end -0.7874 -0.4064)
			(stroke
				(width 0.1524)
				(type default)
			)
			(layer "F.SilkS")
		)
		(fp_line
			(start 0 0.381)
			(end 0 -0.381)
			(stroke
				(width 0.1524)
				(type default)
			)
			(layer "F.SilkS")
		)
		(fp_line
			(start 0.7874 -0.4064)
			(end 0.7874 0.4064)
			(stroke
				(width 0.1524)
				(type default)
			)
			(layer "F.SilkS")
		)
		(fp_line
			(start 0.7874 0.4064)
			(end -0.7874 0.4064)
			(stroke
				(width 0.1524)
				(type default)
			)
			(layer "F.SilkS")
		)
		(fp_poly
			(pts
				(xy -0.5334 0.254) (xy -0.635 0.254) (xy -0.635 0.2286) (xy -0.635 -0.254) (xy -0.5334 -0.254) (xy -0.5334 -0.2794)
				(xy 0.5334 -0.2794) (xy 0.5334 -0.254) (xy 0.635 -0.254) (xy 0.635 0.254) (xy 0.5334 0.254) (xy 0.5334 0.2794)
				(xy -0.508 0.2794) (xy -0.5334 0.2794)
			)
			(stroke
				(width 0)
				(type default)
			)
			(fill no)
			(layer "F.CrtYd")
		)
		(pad "1" smd rect
			(at 0.40005 0)
			(size 0.4572 0.508)
			(layers "F.Cu" "F.Mask" "F.Paste")
			(net "P12V_PDB")
		)
		(pad "2" smd rect
			(at -0.40005 0)
			(size 0.4572 0.508)
			(layers "F.Cu" "F.Mask" "F.Paste")
			(net "GND")
		)
	)
	(footprint ""
		(layer "F.Cu")
		(at 114.849656 -111.43107 90)
		(property "Reference" "PC99"
			(at -1.293622 4.680204 0)
			(unlocked yes)
			(layer "F.SilkS")
			(effects
				(font
					(size 0.7874 0.5842)
					(thickness 0.1524)
				)
				(justify left)
			)
		)
		(property "Value" ""
			(at 0 0 90)
			(layer "F.Fab")
			(effects
				(font
					(size 1.27 1.27)
				)
			)
		)
		(duplicate_pad_numbers_are_jumpers no)
		(fp_line
			(start 2.249932 -4.533392)
			(end 2.249932 4.533392)
			(stroke
				(width 0.1524)
				(type default)
			)
			(layer "F.SilkS")
		)
		(fp_line
			(start -2.249932 -4.533392)
			(end 2.249932 -4.533392)
			(stroke
				(width 0.1524)
				(type default)
			)
			(layer "F.SilkS")
		)
		(fp_line
			(start 2.249932 4.533392)
			(end -2.249932 4.533392)
			(stroke
				(width 0.1524)
				(type default)
			)
			(layer "F.SilkS")
		)
		(fp_line
			(start -2.249932 4.533392)
			(end -2.249932 -4.533392)
			(stroke
				(width 0.1524)
				(type default)
			)
			(layer "F.SilkS")
		)
		(fp_poly
			(pts
				(xy 2.326132 -4.533392) (xy 2.326132 -5.39242) (xy -2.326132 -5.39242) (xy -2.326132 -4.533392)
			)
			(stroke
				(width 0)
				(type default)
			)
			(fill yes)
			(layer "F.SilkS")
		)
		(fp_poly
			(pts
				(xy -1.4605 4.457192) (xy -1.4605 3.750056) (xy -2.249932 3.750056) (xy -2.249932 -3.750056) (xy -1.4605 -3.750056)
				(xy -1.4605 -4.457192) (xy 1.4605 -4.457192) (xy 1.4605 -3.750056) (xy 2.249932 -3.750056) (xy 2.249932 3.750056)
				(xy 1.4605 3.750056) (xy 1.4605 4.457192)
			)
			(stroke
				(width 0)
				(type default)
			)
			(fill no)
			(layer "F.CrtYd")
		)
		(fp_line
			(start 2.249932 -3.750056)
			(end 2.249932 3.750056)
			(stroke
				(width 0.1)
				(type default)
			)
			(layer "F.Fab")
		)
		(fp_line
			(start -2.249932 -3.750056)
			(end 2.249932 -3.750056)
			(stroke
				(width 0.1)
				(type default)
			)
			(layer "F.Fab")
		)
		(fp_line
			(start 2.249932 3.750056)
			(end -2.249932 3.750056)
			(stroke
				(width 0.1)
				(type default)
			)
			(layer "F.Fab")
		)
		(fp_line
			(start -2.249932 3.750056)
			(end -2.249932 -3.750056)
			(stroke
				(width 0.1)
				(type default)
			)
			(layer "F.Fab")
		)
		(fp_text user "+"
			(at 0.29972 -5.594096 180)
			(unlocked yes)
			(layer "F.SilkS")
			(effects
				(font
					(size 1.6002 1.1938)
					(thickness 0.1524)
				)
				(justify left)
			)
		)
		(fp_text user "+"
			(at -0.786384 -6.322314 90)
			(unlocked yes)
			(layer "F.Fab")
			(effects
				(font
					(size 1.905 1.4224)
					(thickness 0.000001)
				)
				(justify left)
			)
		)
		(pad "1" smd rect
			(at 0 -3.199892)
			(size 2.413 2.8194)
			(layers "F.Cu" "F.Mask" "F.Paste")
			(net "PV_VCCP_NODE1")
		)
		(pad "2" smd rect
			(at 0 3.199892)
			(size 2.413 2.8194)
			(layers "F.Cu" "F.Mask" "F.Paste")
			(net "GND")
		)
	)
	(footprint ""
		(layer "F.Cu")
		(at 80.908652 -117.802406)
		(property "Reference" "C1121"
			(at -0.1016 4.228846 90)
			(unlocked yes)
			(layer "F.SilkS")
			(effects
				(font
					(size 0.7874 0.5842)
					(thickness 0.1524)
				)
				(justify left)
			)
		)
		(property "Value" ""
			(at 0 0 0)
			(layer "F.Fab")
			(effects
				(font
					(size 1.27 1.27)
				)
			)
		)
		(duplicate_pad_numbers_are_jumpers no)
		(fp_line
			(start -0.7874 -0.4064)
			(end 0.7874 -0.4064)
			(stroke
				(width 0.1524)
				(type default)
			)
			(layer "F.SilkS")
		)
		(fp_line
			(start -0.7874 0.4064)
			(end -0.7874 -0.4064)
			(stroke
				(width 0.1524)
				(type default)
			)
			(layer "F.SilkS")
		)
		(fp_line
			(start 0 0.381)
			(end 0 -0.381)
			(stroke
				(width 0.1524)
				(type default)
			)
			(layer "F.SilkS")
		)
		(fp_line
			(start 0.7874 -0.4064)
			(end 0.7874 0.4064)
			(stroke
				(width 0.1524)
				(type default)
			)
			(layer "F.SilkS")
		)
		(fp_line
			(start 0.7874 0.4064)
			(end -0.7874 0.4064)
			(stroke
				(width 0.1524)
				(type default)
			)
			(layer "F.SilkS")
		)
		(fp_poly
			(pts
				(xy -0.5334 0.254) (xy -0.635 0.254) (xy -0.635 0.2286) (xy -0.635 -0.254) (xy -0.5334 -0.254) (xy -0.5334 -0.2794)
				(xy 0.5334 -0.2794) (xy 0.5334 -0.254) (xy 0.635 -0.254) (xy 0.635 0.254) (xy 0.5334 0.254) (xy 0.5334 0.2794)
				(xy -0.508 0.2794) (xy -0.5334 0.2794)
			)
			(stroke
				(width 0)
				(type default)
			)
			(fill no)
			(layer "F.CrtYd")
		)
		(pad "1" smd rect
			(at 0.40005 0)
			(size 0.4572 0.508)
			(layers "F.Cu" "F.Mask" "F.Paste")
			(net "P3V3_NODE1")
		)
		(pad "2" smd rect
			(at -0.40005 0)
			(size 0.4572 0.508)
			(layers "F.Cu" "F.Mask" "F.Paste")
			(net "GND")
		)
	)
	(footprint ""
		(layer "F.Cu")
		(at 84.150708 -108.79963 -90)
		(property "Reference" "R1101"
			(at 1.906524 0.75438 0)
			(unlocked yes)
			(layer "F.SilkS")
			(effects
				(font
					(size 0.7874 0.5842)
					(thickness 0.1524)
				)
				(justify left)
			)
		)
		(property "Value" ""
			(at 0 0 270)
			(layer "F.Fab")
			(effects
				(font
					(size 1.27 1.27)
				)
			)
		)
		(duplicate_pad_numbers_are_jumpers no)
		(fp_line
			(start -0.7874 0.4064)
			(end -0.7874 -0.4064)
			(stroke
				(width 0.1524)
				(type default)
			)
			(layer "F.SilkS")
		)
		(fp_line
			(start 0.7874 0.4064)
			(end -0.7874 0.4064)
			(stroke
				(width 0.1524)
				(type default)
			)
			(layer "F.SilkS")
		)
		(fp_line
			(start -0.7874 -0.4064)
			(end 0.7874 -0.4064)
			(stroke
				(width 0.1524)
				(type default)
			)
			(layer "F.SilkS")
		)
		(fp_line
			(start 0.7874 -0.4064)
			(end 0.7874 0.4064)
			(stroke
				(width 0.1524)
				(type default)
			)
			(layer "F.SilkS")
		)
		(fp_poly
			(pts
				(xy -0.508 0.2794) (xy -0.508 0.2286) (xy -0.635 0.2286) (xy -0.635 -0.254) (xy -0.5334 -0.254)
				(xy -0.5334 -0.2794) (xy 0.5334 -0.2794) (xy 0.5334 -0.254) (xy 0.635 -0.254) (xy 0.635 0.254) (xy 0.5334 0.254)
				(xy 0.5334 0.2794)
			)
			(stroke
				(width 0)
				(type default)
			)
			(fill no)
			(layer "F.CrtYd")
		)
		(pad "1" smd rect
			(at 0.40005 0 270)
			(size 0.4572 0.508)
			(layers "F.Cu" "F.Mask" "F.Paste")
			(net "FM_CPLD_NODE1_P3V3_SUS_EN_G")
		)
		(pad "2" smd rect
			(at -0.40005 0 270)
			(size 0.4572 0.508)
			(layers "F.Cu" "F.Mask" "F.Paste")
			(net "P3V3_STB_NODE1")
		)
	)
	(footprint ""
		(layer "F.Cu")
		(at 169.71899 -41.165018 90)
		(property "Reference" "L43"
			(at -1.774952 -1.322832 0)
			(unlocked yes)
			(layer "F.SilkS")
			(effects
				(font
					(size 0.7874 0.5842)
					(thickness 0.1524)
				)
				(justify left)
			)
		)
		(property "Value" ""
			(at 0 0 90)
			(layer "F.Fab")
			(effects
				(font
					(size 1.27 1.27)
				)
			)
		)
		(duplicate_pad_numbers_are_jumpers no)
		(fp_line
			(start 0.989838 -2.0066)
			(end 0.989838 2.0066)
			(stroke
				(width 0.1524)
				(type default)
			)
			(layer "F.SilkS")
		)
		(fp_line
			(start -1.015238 -2.0066)
			(end 0.989838 -2.0066)
			(stroke
				(width 0.1524)
				(type default)
			)
			(layer "F.SilkS")
		)
		(fp_line
			(start 0.989838 2.0066)
			(end -1.015238 2.0066)
			(stroke
				(width 0.1524)
				(type default)
			)
			(layer "F.SilkS")
		)
		(fp_line
			(start -1.015238 2.0066)
			(end -1.015238 -2.0066)
			(stroke
				(width 0.1524)
				(type default)
			)
			(layer "F.SilkS")
		)
		(fp_poly
			(pts
				(xy -0.899922 -1.700022) (xy -0.899922 1.700022) (xy -0.8636 1.700022) (xy -0.8636 1.9304) (xy -0.127 1.9304)
				(xy -0.127 1.700022) (xy 0.127 1.700022) (xy 0.127 1.9304) (xy 0.8636 1.9304) (xy 0.8636 1.700022)
				(xy 0.899922 1.700022) (xy 0.899922 -1.700022) (xy 0.8636 -1.700022) (xy 0.8636 -1.9304) (xy 0.127 -1.9304)
				(xy 0.127 -1.700022) (xy -0.127 -1.700022) (xy -0.127 -1.9304) (xy -0.8636 -1.9304) (xy -0.8636 -1.700022)
			)
			(stroke
				(width 0)
				(type default)
			)
			(fill no)
			(layer "F.CrtYd")
		)
		(fp_line
			(start 0.899922 -1.700022)
			(end 0.899922 1.700022)
			(stroke
				(width 0.1)
				(type default)
			)
			(layer "F.Fab")
		)
		(fp_line
			(start -0.899922 -1.700022)
			(end 0.899922 -1.700022)
			(stroke
				(width 0.1)
				(type default)
			)
			(layer "F.Fab")
		)
		(fp_line
			(start 0.899922 1.700022)
			(end -0.899922 1.700022)
			(stroke
				(width 0.1)
				(type default)
			)
			(layer "F.Fab")
		)
		(fp_line
			(start -0.899922 1.700022)
			(end -0.899922 -1.700022)
			(stroke
				(width 0.1)
				(type default)
			)
			(layer "F.Fab")
		)
		(pad "1" smd rect
			(at -0.499872 -1.400048 90)
			(size 0.6096 0.9144)
			(layers "F.Cu" "F.Mask" "F.Paste")
			(net "USB1_DN")
		)
		(pad "2" smd rect
			(at -0.499872 1.400048 90)
			(size 0.6096 0.9144)
			(layers "F.Cu" "F.Mask" "F.Paste")
			(net "USB1_L_DN")
		)
		(pad "3" smd rect
			(at 0.499872 1.400048 90)
			(size 0.6096 0.9144)
			(layers "F.Cu" "F.Mask" "F.Paste")
			(net "USB1_L_DP")
		)
		(pad "4" smd rect
			(at 0.499872 -1.400048 90)
			(size 0.6096 0.9144)
			(layers "F.Cu" "F.Mask" "F.Paste")
			(net "USB1_DP")
		)
	)
)
